#ISCELL
  mstr_symbols intel_corp_bpage *
  *
#ISCELL
  mstr_standard offpage *
  page143_i10
#ISCELL
  mstr_standard offpage *
  page143_i11
#ISCELL
  mstr_standard offpage *
  page143_i12
#ISCELL
  mstr_standard offpage *
  page143_i13
#ISCELL
  mstr_standard offpage *
  page143_i14
#ISCELL
  mstr_standard offpage *
  page143_i15
#ISCELL
  mstr_standard offpage *
  page143_i16
#ISCELL
  mstr_standard offpage *
  page143_i17
#ISCELL
  mstr_standard offpage *
  page143_i18
#ISCELL
  mstr_standard offpage *
  page143_i19
#ISCELL
  mstr_standard offpage *
  page143_i2
#ISCELL
  mstr_standard offpage *
  page143_i20
#ISCELL
  mstr_standard offpage *
  page143_i21
#ISCELL
  mstr_standard offpage *
  page143_i23
#ISCELL
  mstr_standard offpage *
  page143_i24
#ISCELL
  mstr_standard offpage *
  page143_i25
#ISCELL
  mstr_standard offpage *
  page143_i26
#ISCELL
  mstr_standard offpage *
  page143_i27
#ISCELL
  mstr_standard offpage *
  page143_i28
#ISCELL
  mstr_standard offpage *
  page143_i29
#ISCELL
  mstr_standard offpage *
  page143_i3
#ISCELL
  mstr_standard offpage *
  page143_i30
#ISCELL
  mstr_standard offpage *
  page143_i31
#ISCELL
  mstr_standard offpage *
  page143_i33
#ISCELL
  mstr_standard offpage *
  page143_i34
#ISCELL
  mstr_standard offpage *
  page143_i36
#ISCELL
  mstr_standard offpage *
  page143_i37
#ISCELL
  mstr_standard offpage *
  page143_i38
#ISCELL
  mstr_standard offpage *
  page143_i39
#ISCELL
  mstr_standard offpage *
  page143_i4
#ISCELL
  mstr_standard offpage *
  page143_i40
#ISCELL
  mstr_standard offpage *
  page143_i41
#ISCELL
  mstr_standard offpage *
  page143_i42
#ISCELL
  mstr_standard offpage *
  page143_i43
#ISCELL
  mstr_standard offpage *
  page143_i44
#ISCELL
  mstr_standard offpage *
  page143_i45
#ISCELL
  mstr_standard offpage *
  page143_i46
#ISCELL
  mstr_standard offpage *
  page143_i47
#ISCELL
  mstr_standard offpage *
  page143_i48
#ISCELL
  mstr_standard offpage *
  page143_i49
#ISCELL
  mstr_standard offpage *
  page143_i5
#ISCELL
  mstr_standard offpage *
  page143_i50
#ISCELL
  mstr_standard offpage *
  page143_i51
#ISCELL
  mstr_standard offpage *
  page143_i52
#ISCELL
  mstr_symbols gnd *
  page143_i54
#CELL
  mstr_discrete cap *
  page143_i55
#ISCELL
  mstr_symbols gnd *
  page143_i57
#CELL
  mstr_discrete res *
  page143_i58
#ISCELL
  mstr_standard offpage *
  page143_i59
#ISCELL
  mstr_standard offpage *
  page143_i6
#ISCELL
  mstr_standard offpage *
  page143_i60
#ISCELL
  mstr_standard offpage *
  page143_i61
#ISCELL
  mstr_standard offpage *
  page143_i62
#CELL
  w_hdl ast2520a1-gp-gp *
  page143_i63
#ISCELL
  mstr_standard offpage *
  page143_i7
#ISCELL
  mstr_standard offpage *
  page143_i8
#ISCELL
  mstr_standard offpage *
  page143_i9
